FILE_TYPE=LIBRARY_PARTS;
primitive 'BAS70057F';
  pin
    'A':
      PIN_NUMBER='(2)';
      INPUT_LOAD='(-0.01,0.01)';
    'B':
      PIN_NUMBER='(1)';
      INPUT_LOAD='(-0.01,0.01)';
    'C':
      PIN_NUMBER='(3)';
      BIDIRECTIONAL='TRUE';
      INPUT_LOAD='(-0.01,0.01)';
      OUTPUT_LOAD='(1.0,-1.0)';
  end_pin;
  body
    PART_NAME='BAS70057F';
    BODY_NAME='BAS70057F';
    PHYS_DES_PREFIX='U';
    CLASS='IC';
  end_body;
end_primitive;

END.
